(kicad_pcb
	(version 20260206)
	(generator "pcbnew")
	(generator_version "10.0")
	(general
		(thickness 1.6)
		(legacy_teardrops no)
	)
	(paper "A4")
	(title_block
		(title "panther-plus-userver — 13130-1b_20150205.brd")
		(comment 1 "Honey Badger (Wiwynn) / footprint 406 of 1509 (DIMM2), pads 163-169 of 210")
	)
	(layers
		(0 "F.Cu" signal "TOP")
		(4 "In1.Cu" signal "L2")
		(6 "In2.Cu" signal "L3")
		(8 "In3.Cu" signal "L4")
		(10 "In4.Cu" signal "L5")
		(12 "In5.Cu" signal "L6")
		(14 "In6.Cu" signal "L7")
		(16 "In7.Cu" signal "L8")
		(18 "In8.Cu" signal "L9")
		(20 "In9.Cu" signal "L10")
		(22 "In10.Cu" signal "L11")
		(2 "B.Cu" signal "BOTTOM")
		(9 "F.Adhes" user "F.Adhesive")
		(11 "B.Adhes" user "B.Adhesive")
		(13 "F.Paste" user "Package Geometry/Pastemask Top")
		(15 "B.Paste" user "Package Geometry/Pastemask Bottom")
		(5 "F.SilkS" user "Ref Des/Silkscreen Top")
		(7 "B.SilkS" user "Ref Des/Silkscreen Bottom")
		(1 "F.Mask" user "Board Geometry/Soldermask Top")
		(3 "B.Mask" user "Board Geometry/Soldermask Bottom")
		(17 "Dwgs.User" user "User.Drawings")
		(19 "Cmts.User" user "User.Comments")
		(21 "Eco1.User" user "User.Eco1")
		(23 "Eco2.User" user "User.Eco2")
		(25 "Edge.Cuts" user "Board Geometry/Outline")
		(27 "Margin" user)
		(31 "F.CrtYd" user "Package Geometry/Place Bound Top")
		(29 "B.CrtYd" user "Package Geometry/Place Bound Bottom")
		(35 "F.Fab" user "Ref Des/Assembly Top")
		(33 "B.Fab" user "Ref Des/Assembly Bottom")
	)
	(footprint ""
		(layer "F.Cu")
		(at 158.500064 -66.699892 180)
		(property "Reference" "DIMM2"
			(at 0 0 180)
			(layer "F.SilkS")
			(hide yes)
			(effects
				(font
					(size 1.27 1.27)
				)
			)
		)
		(property "Value" "DDR3-204P-174-COLAY-1-GP"
			(at -40.682164 -17.468088 180)
			(unlocked yes)
			(layer "F.Fab")
			(hide yes)
			(effects
				(font
					(size 1.016 1.016)
					(thickness 0.1524)
				)
			)
		)
		(property "Device Type" "AS0A626-H8SN-7H-COLAY-1"
			(at -40.682164 -18.992088 180)
			(unlocked yes)
			(layer "F.Fab")
			(hide yes)
			(effects
				(font
					(size 1.016 1.016)
					(thickness 0.1524)
				)
			)
		)
		(duplicate_pad_numbers_are_jumpers no)
		(pad "161" smd custom
			(at 18.750026 4.106672 180)
			(size 0.1143 0.1143)
			(layers "F.Cu" "F.Mask" "F.Paste")
			(net "M_A_DQ47")
			(options
				(clearance outline)
				(anchor circle)
			)
			(primitives
				(gr_poly
					(pts
						(xy 0 0.9017) (xy -0.03175 0.89916) (xy -0.0635 0.889) (xy -0.09144 0.87376) (xy -0.11684 0.85344)
						(xy -0.13716 0.82804) (xy -0.1524 0.8001) (xy -0.16256 0.76835) (xy -0.1651 0.7366) (xy -0.1651 -0.13462)
						(xy -0.17272 -0.14224) (xy -0.19812 -0.1778) (xy -0.2032 -0.18796) (xy -0.20701 -0.19685) (xy -0.21209 -0.20701)
						(xy -0.2159 -0.21717) (xy -0.21844 -0.22733) (xy -0.22225 -0.23876) (xy -0.22352 -0.24892) (xy -0.22606 -0.25908)
						(xy -0.22733 -0.27051) (xy -0.22733 -0.28067) (xy -0.2286 -0.2921) (xy -0.22733 -0.30353) (xy -0.22733 -0.31369)
						(xy -0.22606 -0.32512) (xy -0.22352 -0.33528) (xy -0.22225 -0.34544) (xy -0.21844 -0.35687) (xy -0.2159 -0.36703)
						(xy -0.21209 -0.37719) (xy -0.20701 -0.38735) (xy -0.2032 -0.39624) (xy -0.19812 -0.4064) (xy -0.17272 -0.44196)
						(xy -0.1651 -0.44958) (xy -0.1651 -0.7366) (xy -0.16256 -0.76835) (xy -0.1524 -0.8001) (xy -0.13716 -0.82804)
						(xy -0.11684 -0.85344) (xy -0.09144 -0.87376) (xy -0.0635 -0.889) (xy -0.03175 -0.89916) (xy 0 -0.9017)
						(xy 0.03175 -0.89916) (xy 0.0635 -0.889) (xy 0.09144 -0.87376) (xy 0.11684 -0.85344) (xy 0.13716 -0.82804)
						(xy 0.1524 -0.8001) (xy 0.16256 -0.76835) (xy 0.1651 -0.7366) (xy 0.1651 -0.44958) (xy 0.17272 -0.44196)
						(xy 0.19812 -0.4064) (xy 0.2032 -0.39624) (xy 0.20701 -0.38735) (xy 0.21209 -0.37719) (xy 0.2159 -0.36703)
						(xy 0.21844 -0.35687) (xy 0.22225 -0.34544) (xy 0.22352 -0.33528) (xy 0.22606 -0.32512) (xy 0.22733 -0.31369)
						(xy 0.22733 -0.30353) (xy 0.2286 -0.2921) (xy 0.22733 -0.28067) (xy 0.22733 -0.27051) (xy 0.22606 -0.25908)
						(xy 0.22352 -0.24892) (xy 0.22225 -0.23876) (xy 0.21844 -0.22733) (xy 0.2159 -0.21717) (xy 0.21209 -0.20701)
						(xy 0.20701 -0.19685) (xy 0.2032 -0.18796) (xy 0.19812 -0.1778) (xy 0.17272 -0.14224) (xy 0.1651 -0.13462)
						(xy 0.1651 0.7366) (xy 0.16256 0.76835) (xy 0.1524 0.8001) (xy 0.13716 0.82804) (xy 0.11684 0.85344)
						(xy 0.09144 0.87376) (xy 0.0635 0.889) (xy 0.03175 0.89916)
					)
					(width 0)
					(fill yes)
				)
			)
		)
		(pad "162" smd custom
			(at 19.05 -4.106672 180)
			(size 0.1143 0.1143)
			(layers "F.Cu" "F.Mask" "F.Paste")
			(net "M_A_DQ43")
			(options
				(clearance outline)
				(anchor circle)
			)
			(primitives
				(gr_poly
					(pts
						(xy 0 0.9017) (xy -0.03175 0.89916) (xy -0.0635 0.889) (xy -0.09144 0.87376) (xy -0.11684 0.85344)
						(xy -0.13716 0.82804) (xy -0.1524 0.8001) (xy -0.16256 0.76835) (xy -0.1651 0.7366) (xy -0.1651 0.44958)
						(xy -0.17272 0.44196) (xy -0.19812 0.4064) (xy -0.2032 0.39624) (xy -0.20701 0.38735) (xy -0.21209 0.37719)
						(xy -0.2159 0.36703) (xy -0.21844 0.35687) (xy -0.22225 0.34544) (xy -0.22352 0.33528) (xy -0.22606 0.32512)
						(xy -0.22733 0.31369) (xy -0.22733 0.30353) (xy -0.2286 0.2921) (xy -0.22733 0.28067) (xy -0.22733 0.27051)
						(xy -0.22606 0.25908) (xy -0.22352 0.24892) (xy -0.22225 0.23876) (xy -0.21844 0.22733) (xy -0.2159 0.21717)
						(xy -0.21209 0.20701) (xy -0.20701 0.19685) (xy -0.2032 0.18796) (xy -0.19812 0.1778) (xy -0.17272 0.14224)
						(xy -0.1651 0.13462) (xy -0.1651 -0.7366) (xy -0.16256 -0.76835) (xy -0.1524 -0.8001) (xy -0.13716 -0.82804)
						(xy -0.11684 -0.85344) (xy -0.09144 -0.87376) (xy -0.0635 -0.889) (xy -0.03175 -0.89916) (xy 0 -0.9017)
						(xy 0.03175 -0.89916) (xy 0.0635 -0.889) (xy 0.09144 -0.87376) (xy 0.11684 -0.85344) (xy 0.13716 -0.82804)
						(xy 0.1524 -0.8001) (xy 0.16256 -0.76835) (xy 0.1651 -0.7366) (xy 0.1651 0.13462) (xy 0.17272 0.14224)
						(xy 0.19812 0.1778) (xy 0.2032 0.18796) (xy 0.20701 0.19685) (xy 0.21209 0.20701) (xy 0.2159 0.21717)
						(xy 0.21844 0.22733) (xy 0.22225 0.23876) (xy 0.22352 0.24892) (xy 0.22606 0.25908) (xy 0.22733 0.27051)
						(xy 0.22733 0.28067) (xy 0.2286 0.2921) (xy 0.22733 0.30353) (xy 0.22733 0.31369) (xy 0.22606 0.32512)
						(xy 0.22352 0.33528) (xy 0.22225 0.34544) (xy 0.21844 0.35687) (xy 0.2159 0.36703) (xy 0.21209 0.37719)
						(xy 0.20701 0.38735) (xy 0.2032 0.39624) (xy 0.19812 0.4064) (xy 0.17272 0.44196) (xy 0.1651 0.44958)
						(xy 0.1651 0.7366) (xy 0.16256 0.76835) (xy 0.1524 0.8001) (xy 0.13716 0.82804) (xy 0.11684 0.85344)
						(xy 0.09144 0.87376) (xy 0.0635 0.889) (xy 0.03175 0.89916)
					)
					(width 0)
					(fill yes)
				)
			)
		)
		(pad "163" smd custom
			(at 19.349974 4.106672 180)
			(size 0.1143 0.1143)
			(layers "F.Cu" "F.Mask" "F.Paste")
			(net "GND")
			(options
				(clearance outline)
				(anchor circle)
			)
			(primitives
				(gr_poly
					(pts
						(xy 0 0.9017) (xy -0.03175 0.89916) (xy -0.0635 0.889) (xy -0.09144 0.87376) (xy -0.11684 0.85344)
						(xy -0.13716 0.82804) (xy -0.1524 0.8001) (xy -0.16256 0.76835) (xy -0.1651 0.7366) (xy -0.1651 0.11938)
						(xy -0.17272 0.11176) (xy -0.19812 0.0762) (xy -0.2032 0.06604) (xy -0.20701 0.05715) (xy -0.21209 0.04699)
						(xy -0.2159 0.03683) (xy -0.21844 0.02667) (xy -0.22225 0.01524) (xy -0.22352 0.00508) (xy -0.22606 -0.00508)
						(xy -0.22733 -0.01651) (xy -0.22733 -0.02667) (xy -0.2286 -0.0381) (xy -0.22733 -0.04953) (xy -0.22733 -0.05969)
						(xy -0.22606 -0.07112) (xy -0.22352 -0.08128) (xy -0.22225 -0.09144) (xy -0.21844 -0.10287) (xy -0.2159 -0.11303)
						(xy -0.21209 -0.12319) (xy -0.20701 -0.13335) (xy -0.2032 -0.14224) (xy -0.19812 -0.1524) (xy -0.17272 -0.18796)
						(xy -0.1651 -0.19558) (xy -0.1651 -0.7366) (xy -0.16256 -0.76835) (xy -0.1524 -0.8001) (xy -0.13716 -0.82804)
						(xy -0.11684 -0.85344) (xy -0.09144 -0.87376) (xy -0.0635 -0.889) (xy -0.03175 -0.89916) (xy 0 -0.9017)
						(xy 0.03175 -0.89916) (xy 0.0635 -0.889) (xy 0.09144 -0.87376) (xy 0.11684 -0.85344) (xy 0.13716 -0.82804)
						(xy 0.1524 -0.8001) (xy 0.16256 -0.76835) (xy 0.1651 -0.7366) (xy 0.1651 -0.19685) (xy 0.17272 -0.18923)
						(xy 0.17907 -0.18034) (xy 0.18669 -0.17145) (xy 0.19177 -0.16256) (xy 0.19812 -0.15367) (xy 0.20828 -0.13335)
						(xy 0.21971 -0.10287) (xy 0.22225 -0.09271) (xy 0.22479 -0.08128) (xy 0.22606 -0.07112) (xy 0.2286 -0.05969)
						(xy 0.2286 -0.01651) (xy 0.22606 -0.00508) (xy 0.22479 0.00508) (xy 0.22225 0.01651) (xy 0.21971 0.02667)
						(xy 0.20828 0.05715) (xy 0.19812 0.07747) (xy 0.19177 0.08636) (xy 0.18669 0.09525) (xy 0.17907 0.10414)
						(xy 0.17272 0.11303) (xy 0.1651 0.12065) (xy 0.1651 0.7366) (xy 0.16256 0.76835) (xy 0.1524 0.8001)
						(xy 0.13716 0.82804) (xy 0.11684 0.85344) (xy 0.09144 0.87376) (xy 0.0635 0.889) (xy 0.03175 0.89916)
					)
					(width 0)
					(fill yes)
				)
			)
		)
		(pad "164" smd custom
			(at 19.649948 -4.106672 180)
			(size 0.1143 0.1143)
			(layers "F.Cu" "F.Mask" "F.Paste")
			(net "GND")
			(options
				(clearance outline)
				(anchor circle)
			)
			(primitives
				(gr_poly
					(pts
						(xy 0 0.9017) (xy -0.03175 0.89916) (xy -0.0635 0.889) (xy -0.09144 0.87376) (xy -0.11684 0.85344)
						(xy -0.13716 0.82804) (xy -0.1524 0.8001) (xy -0.16256 0.76835) (xy -0.1651 0.7366) (xy -0.1651 0.19685)
						(xy -0.17272 0.18923) (xy -0.17907 0.18034) (xy -0.18669 0.17145) (xy -0.19177 0.16256) (xy -0.19812 0.15367)
						(xy -0.20828 0.13335) (xy -0.21971 0.10287) (xy -0.22225 0.09271) (xy -0.22479 0.08128) (xy -0.22606 0.07112)
						(xy -0.2286 0.05969) (xy -0.2286 0.01651) (xy -0.22606 0.00508) (xy -0.22479 -0.00508) (xy -0.22225 -0.01651)
						(xy -0.21971 -0.02667) (xy -0.20828 -0.05715) (xy -0.19812 -0.07747) (xy -0.19177 -0.08636) (xy -0.18669 -0.09525)
						(xy -0.17907 -0.10414) (xy -0.17272 -0.11303) (xy -0.1651 -0.12065) (xy -0.1651 -0.7366) (xy -0.16256 -0.76835)
						(xy -0.1524 -0.8001) (xy -0.13716 -0.82804) (xy -0.11684 -0.85344) (xy -0.09144 -0.87376) (xy -0.0635 -0.889)
						(xy -0.03175 -0.89916) (xy 0 -0.9017) (xy 0.03175 -0.89916) (xy 0.0635 -0.889) (xy 0.09144 -0.87376)
						(xy 0.11684 -0.85344) (xy 0.13716 -0.82804) (xy 0.1524 -0.8001) (xy 0.16256 -0.76835) (xy 0.1651 -0.7366)
						(xy 0.1651 -0.11938) (xy 0.17272 -0.11176) (xy 0.19812 -0.0762) (xy 0.2032 -0.06604) (xy 0.20701 -0.05715)
						(xy 0.21209 -0.04699) (xy 0.2159 -0.03683) (xy 0.21844 -0.02667) (xy 0.22225 -0.01524) (xy 0.22352 -0.00508)
						(xy 0.22606 0.00508) (xy 0.22733 0.01651) (xy 0.22733 0.02667) (xy 0.2286 0.0381) (xy 0.22733 0.04953)
						(xy 0.22733 0.05969) (xy 0.22606 0.07112) (xy 0.22352 0.08128) (xy 0.22225 0.09144) (xy 0.21844 0.10287)
						(xy 0.2159 0.11303) (xy 0.21209 0.12319) (xy 0.20701 0.13335) (xy 0.2032 0.14224) (xy 0.19812 0.1524)
						(xy 0.17272 0.18796) (xy 0.1651 0.19558) (xy 0.1651 0.7366) (xy 0.16256 0.76835) (xy 0.1524 0.8001)
						(xy 0.13716 0.82804) (xy 0.11684 0.85344) (xy 0.09144 0.87376) (xy 0.0635 0.889) (xy 0.03175 0.89916)
					)
					(width 0)
					(fill yes)
				)
			)
		)
		(pad "165" smd custom
			(at 19.949922 4.106672 180)
			(size 0.1143 0.1143)
			(layers "F.Cu" "F.Mask" "F.Paste")
			(net "M_A_DQ52")
			(options
				(clearance outline)
				(anchor circle)
			)
			(primitives
				(gr_poly
					(pts
						(xy 0 0.9017) (xy -0.03175 0.89916) (xy -0.0635 0.889) (xy -0.09144 0.87376) (xy -0.11684 0.85344)
						(xy -0.13716 0.82804) (xy -0.1524 0.8001) (xy -0.16256 0.76835) (xy -0.1651 0.7366) (xy -0.1651 -0.13462)
						(xy -0.17272 -0.14224) (xy -0.19812 -0.1778) (xy -0.2032 -0.18796) (xy -0.20701 -0.19685) (xy -0.21209 -0.20701)
						(xy -0.2159 -0.21717) (xy -0.21844 -0.22733) (xy -0.22225 -0.23876) (xy -0.22352 -0.24892) (xy -0.22606 -0.25908)
						(xy -0.22733 -0.27051) (xy -0.22733 -0.28067) (xy -0.2286 -0.2921) (xy -0.22733 -0.30353) (xy -0.22733 -0.31369)
						(xy -0.22606 -0.32512) (xy -0.22352 -0.33528) (xy -0.22225 -0.34544) (xy -0.21844 -0.35687) (xy -0.2159 -0.36703)
						(xy -0.21209 -0.37719) (xy -0.20701 -0.38735) (xy -0.2032 -0.39624) (xy -0.19812 -0.4064) (xy -0.17272 -0.44196)
						(xy -0.1651 -0.44958) (xy -0.1651 -0.7366) (xy -0.16256 -0.76835) (xy -0.1524 -0.8001) (xy -0.13716 -0.82804)
						(xy -0.11684 -0.85344) (xy -0.09144 -0.87376) (xy -0.0635 -0.889) (xy -0.03175 -0.89916) (xy 0 -0.9017)
						(xy 0.03175 -0.89916) (xy 0.0635 -0.889) (xy 0.09144 -0.87376) (xy 0.11684 -0.85344) (xy 0.13716 -0.82804)
						(xy 0.1524 -0.8001) (xy 0.16256 -0.76835) (xy 0.1651 -0.7366) (xy 0.1651 -0.44958) (xy 0.17272 -0.44196)
						(xy 0.19812 -0.4064) (xy 0.2032 -0.39624) (xy 0.20701 -0.38735) (xy 0.21209 -0.37719) (xy 0.2159 -0.36703)
						(xy 0.21844 -0.35687) (xy 0.22225 -0.34544) (xy 0.22352 -0.33528) (xy 0.22606 -0.32512) (xy 0.22733 -0.31369)
						(xy 0.22733 -0.30353) (xy 0.2286 -0.2921) (xy 0.22733 -0.28067) (xy 0.22733 -0.27051) (xy 0.22606 -0.25908)
						(xy 0.22352 -0.24892) (xy 0.22225 -0.23876) (xy 0.21844 -0.22733) (xy 0.2159 -0.21717) (xy 0.21209 -0.20701)
						(xy 0.20701 -0.19685) (xy 0.2032 -0.18796) (xy 0.19812 -0.1778) (xy 0.17272 -0.14224) (xy 0.1651 -0.13462)
						(xy 0.1651 0.7366) (xy 0.16256 0.76835) (xy 0.1524 0.8001) (xy 0.13716 0.82804) (xy 0.11684 0.85344)
						(xy 0.09144 0.87376) (xy 0.0635 0.889) (xy 0.03175 0.89916)
					)
					(width 0)
					(fill yes)
				)
			)
		)
		(pad "166" smd custom
			(at 20.249896 -4.106672 180)
			(size 0.1143 0.1143)
			(layers "F.Cu" "F.Mask" "F.Paste")
			(net "M_A_DQ48")
			(options
				(clearance outline)
				(anchor circle)
			)
			(primitives
				(gr_poly
					(pts
						(xy 0 0.9017) (xy -0.03175 0.89916) (xy -0.0635 0.889) (xy -0.09144 0.87376) (xy -0.11684 0.85344)
						(xy -0.13716 0.82804) (xy -0.1524 0.8001) (xy -0.16256 0.76835) (xy -0.1651 0.7366) (xy -0.1651 0.44958)
						(xy -0.17272 0.44196) (xy -0.19812 0.4064) (xy -0.2032 0.39624) (xy -0.20701 0.38735) (xy -0.21209 0.37719)
						(xy -0.2159 0.36703) (xy -0.21844 0.35687) (xy -0.22225 0.34544) (xy -0.22352 0.33528) (xy -0.22606 0.32512)
						(xy -0.22733 0.31369) (xy -0.22733 0.30353) (xy -0.2286 0.2921) (xy -0.22733 0.28067) (xy -0.22733 0.27051)
						(xy -0.22606 0.25908) (xy -0.22352 0.24892) (xy -0.22225 0.23876) (xy -0.21844 0.22733) (xy -0.2159 0.21717)
						(xy -0.21209 0.20701) (xy -0.20701 0.19685) (xy -0.2032 0.18796) (xy -0.19812 0.1778) (xy -0.17272 0.14224)
						(xy -0.1651 0.13462) (xy -0.1651 -0.7366) (xy -0.16256 -0.76835) (xy -0.1524 -0.8001) (xy -0.13716 -0.82804)
						(xy -0.11684 -0.85344) (xy -0.09144 -0.87376) (xy -0.0635 -0.889) (xy -0.03175 -0.89916) (xy 0 -0.9017)
						(xy 0.03175 -0.89916) (xy 0.0635 -0.889) (xy 0.09144 -0.87376) (xy 0.11684 -0.85344) (xy 0.13716 -0.82804)
						(xy 0.1524 -0.8001) (xy 0.16256 -0.76835) (xy 0.1651 -0.7366) (xy 0.1651 0.13462) (xy 0.17272 0.14224)
						(xy 0.19812 0.1778) (xy 0.2032 0.18796) (xy 0.20701 0.19685) (xy 0.21209 0.20701) (xy 0.2159 0.21717)
						(xy 0.21844 0.22733) (xy 0.22225 0.23876) (xy 0.22352 0.24892) (xy 0.22606 0.25908) (xy 0.22733 0.27051)
						(xy 0.22733 0.28067) (xy 0.2286 0.2921) (xy 0.22733 0.30353) (xy 0.22733 0.31369) (xy 0.22606 0.32512)
						(xy 0.22352 0.33528) (xy 0.22225 0.34544) (xy 0.21844 0.35687) (xy 0.2159 0.36703) (xy 0.21209 0.37719)
						(xy 0.20701 0.38735) (xy 0.2032 0.39624) (xy 0.19812 0.4064) (xy 0.17272 0.44196) (xy 0.1651 0.44958)
						(xy 0.1651 0.7366) (xy 0.16256 0.76835) (xy 0.1524 0.8001) (xy 0.13716 0.82804) (xy 0.11684 0.85344)
						(xy 0.09144 0.87376) (xy 0.0635 0.889) (xy 0.03175 0.89916)
					)
					(width 0)
					(fill yes)
				)
			)
		)
		(pad "167" smd custom
			(at 20.550124 4.106672 180)
			(size 0.1143 0.1143)
			(layers "F.Cu" "F.Mask" "F.Paste")
			(net "M_A_DQ53")
			(options
				(clearance outline)
				(anchor circle)
			)
			(primitives
				(gr_poly
					(pts
						(xy 0 0.9017) (xy -0.03175 0.89916) (xy -0.0635 0.889) (xy -0.09144 0.87376) (xy -0.11684 0.85344)
						(xy -0.13716 0.82804) (xy -0.1524 0.8001) (xy -0.16256 0.76835) (xy -0.1651 0.7366) (xy -0.1651 0.11938)
						(xy -0.17272 0.11176) (xy -0.19812 0.0762) (xy -0.2032 0.06604) (xy -0.20701 0.05715) (xy -0.21209 0.04699)
						(xy -0.2159 0.03683) (xy -0.21844 0.02667) (xy -0.22225 0.01524) (xy -0.22352 0.00508) (xy -0.22606 -0.00508)
						(xy -0.22733 -0.01651) (xy -0.22733 -0.02667) (xy -0.2286 -0.0381) (xy -0.22733 -0.04953) (xy -0.22733 -0.05969)
						(xy -0.22606 -0.07112) (xy -0.22352 -0.08128) (xy -0.22225 -0.09144) (xy -0.21844 -0.10287) (xy -0.2159 -0.11303)
						(xy -0.21209 -0.12319) (xy -0.20701 -0.13335) (xy -0.2032 -0.14224) (xy -0.19812 -0.1524) (xy -0.17272 -0.18796)
						(xy -0.1651 -0.19558) (xy -0.1651 -0.7366) (xy -0.16256 -0.76835) (xy -0.1524 -0.8001) (xy -0.13716 -0.82804)
						(xy -0.11684 -0.85344) (xy -0.09144 -0.87376) (xy -0.0635 -0.889) (xy -0.03175 -0.89916) (xy 0 -0.9017)
						(xy 0.03175 -0.89916) (xy 0.0635 -0.889) (xy 0.09144 -0.87376) (xy 0.11684 -0.85344) (xy 0.13716 -0.82804)
						(xy 0.1524 -0.8001) (xy 0.16256 -0.76835) (xy 0.1651 -0.7366) (xy 0.1651 -0.19685) (xy 0.17272 -0.18923)
						(xy 0.17907 -0.18034) (xy 0.18669 -0.17145) (xy 0.19177 -0.16256) (xy 0.19812 -0.15367) (xy 0.20828 -0.13335)
						(xy 0.21971 -0.10287) (xy 0.22225 -0.09271) (xy 0.22479 -0.08128) (xy 0.22606 -0.07112) (xy 0.2286 -0.05969)
						(xy 0.2286 -0.01651) (xy 0.22606 -0.00508) (xy 0.22479 0.00508) (xy 0.22225 0.01651) (xy 0.21971 0.02667)
						(xy 0.20828 0.05715) (xy 0.19812 0.07747) (xy 0.19177 0.08636) (xy 0.18669 0.09525) (xy 0.17907 0.10414)
						(xy 0.17272 0.11303) (xy 0.1651 0.12065) (xy 0.1651 0.7366) (xy 0.16256 0.76835) (xy 0.1524 0.8001)
						(xy 0.13716 0.82804) (xy 0.11684 0.85344) (xy 0.09144 0.87376) (xy 0.0635 0.889) (xy 0.03175 0.89916)
					)
					(width 0)
					(fill yes)
				)
			)
		)
	)
)
